#ISCELL
  pure_quanta quanta_title_block_c *
  *
#ISCELL
  pure_quanta_power gnd *
  page244_i1
#CELL
  pure_quanta q_cap *
  page244_i10
#CELL
  pure_quanta q_cap *
  page244_i11
#CELL
  pure_quanta q_cap *
  page244_i13
#ISCELL
  pure_quanta_power gnd *
  page244_i14
#CELL
  pure_quanta q_res *
  page244_i15
#ISCELL
  pure_quanta_power gnd *
  page244_i16
#ISCELL
  pure_quanta_power gnd *
  page244_i17
#ISCELL
  pure_quanta_power gnd *
  page244_i18
#CELL
  pure_quanta q_cap *
  page244_i19
#CELL
  pure_quanta q_cap *
  page244_i2
#CELL
  pure_quanta q_cap *
  page244_i20
#ISCELL
  pure_quanta_power gnd *
  page244_i21
#ISCELL
  pure_quanta_power gnd *
  page244_i22
#CELL
  pure_quanta q_res *
  page244_i23
#CELL
  pure_quanta q_cap *
  page244_i24
#CELL
  pure_quanta q_res *
  page244_i25
#CELL
  pure_quanta q_res *
  page244_i26
#CELL
  pure_quanta q_res *
  page244_i27
#CELL
  pure_quanta q_inductor *
  page244_i28
#ISCELL
  standard offpage *
  page244_i29
#ISCELL
  pure_quanta_power p1v0_aux *
  page244_i3
#CELL
  pure_quanta q_capp *
  page244_i30
#CELL
  pure_quanta q_cap *
  page244_i31
#CELL
  pure_quanta q_cap *
  page244_i32
#ISCELL
  pure_quanta_power gnd *
  page244_i33
#CELL
  pure_quanta q_cap *
  page244_i34
#ISCELL
  pure_quanta_power universal_power *
  page244_i35
#ISCELL
  pure_quanta_power p1v0 *
  page244_i36
#CELL
  pure_quanta q_res *
  page244_i37
#CELL
  pure_quanta mpq8633aglec807z *
  page244_i38
#ISCELL
  standard offpage *
  page244_i39
#ISCELL
  pure_quanta_power gnd *
  page244_i4
#CELL
  pure_quanta q_res *
  page244_i40
#CELL
  pure_quanta q_inductor *
  page244_i5
#ISCELL
  pure_quanta_power gnd *
  page244_i6
#CELL
  pure_quanta q_cap *
  page244_i7
#CELL
  pure_quanta q_cap *
  page244_i8
#ISCELL
  pure_quanta_power universal_power *
  page244_i9
